(kicad_pcb
	(version 20241229)
	(generator "pcbnew")
	(generator_version "9.0")
	(general
		(thickness 1.711)
		(legacy_teardrops no)
	)
	(paper "A4")
	(title_block
		(title "Antmicro Baseboard for Jetson AGX Thor")
		(date "2026-02-18")
		(rev "1.1.0")
		(company "Antmicro Ltd")
		(comment 1 "www.antmicro.com")
		(comment 9 "footprint 956 of 1170 (J14), pads 1-71 of 71")
	)
	(layers
		(0 "F.Cu" signal)
		(4 "In1.Cu" signal)
		(6 "In2.Cu" signal)
		(8 "In3.Cu" signal)
		(10 "In4.Cu" jumper)
		(12 "In5.Cu" signal)
		(14 "In6.Cu" signal)
		(16 "In7.Cu" signal)
		(18 "In8.Cu" signal)
		(2 "B.Cu" signal)
		(9 "F.Adhes" user "F.Adhesive")
		(11 "B.Adhes" user "B.Adhesive")
		(13 "F.Paste" user)
		(15 "B.Paste" user)
		(5 "F.SilkS" user "F.Silkscreen")
		(7 "B.SilkS" user "B.Silkscreen")
		(1 "F.Mask" user)
		(3 "B.Mask" user)
		(17 "Dwgs.User" user "User.Drawings")
		(19 "Cmts.User" user "User.Comments")
		(21 "Eco1.User" user "User.Eco1")
		(23 "Eco2.User" user "User.Eco2")
		(25 "Edge.Cuts" user)
		(27 "Margin" user)
		(31 "F.CrtYd" user "F.Courtyard")
		(29 "B.CrtYd" user "B.Courtyard")
		(35 "F.Fab" user)
		(33 "B.Fab" user)
	)
	(footprint "antmicro-footprints:Bus_M.2_Socket_Key_E_TE_2199230-6"
		(locked yes)
		(layer "B.Cu")
		(at 117.46 129.51 -90)
		(property "Reference" "J14"
			(at 11.45 -5.015 0)
			(layer "B.SilkS")
			(effects
				(font
					(size 0.7 0.7)
					(thickness 0.15)
				)
				(justify left bottom mirror)
			)
		)
		(property "Value" "Bus_M.2_2199230-2"
			(at -10.999 -5.75 90)
			(layer "B.Fab")
			(effects
				(font
					(size 0.7 0.7)
					(thickness 0.15)
				)
				(justify left bottom mirror)
			)
		)
		(property "Datasheet" "https://eu.mouser.com/datasheet/2/418/9/ENG_DS_1_1773702_1NGFFQRG_EN_0214_1_1773702_1NGFF_-3328593.pdf"
			(at 0 0 90)
			(layer "B.Fab")
			(hide yes)
			(effects
				(font
					(size 1.27 1.27)
					(thickness 0.15)
				)
				(justify mirror)
			)
		)
		(property "Description" "Key E, PCI connector"
			(at 0 0 90)
			(layer "B.Fab")
			(hide yes)
			(effects
				(font
					(size 1.27 1.27)
					(thickness 0.15)
				)
				(justify mirror)
			)
		)
		(property "MPN" "2199230-2"
			(at 0 0 90)
			(unlocked yes)
			(layer "B.Fab")
			(hide yes)
			(effects
				(font
					(size 1 1)
					(thickness 0.15)
				)
				(justify mirror)
			)
		)
		(property "Manufacturer" "TE Connectivity"
			(at 0 0 90)
			(unlocked yes)
			(layer "B.Fab")
			(hide yes)
			(effects
				(font
					(size 1 1)
					(thickness 0.15)
				)
				(justify mirror)
			)
		)
		(property "Author" "Antmicro"
			(at 0 0 90)
			(unlocked yes)
			(layer "B.Fab")
			(hide yes)
			(effects
				(font
					(size 1 1)
					(thickness 0.15)
				)
				(justify mirror)
			)
		)
		(property "License" "Apache-2.0"
			(at 0 0 90)
			(unlocked yes)
			(layer "B.Fab")
			(hide yes)
			(effects
				(font
					(size 1 1)
					(thickness 0.15)
				)
				(justify mirror)
			)
		)
		(sheetname "/M.2/")
		(sheetfile "m2.kicad_sch")
		(attr smd)
		(pad "" np_thru_hole circle
			(at -9.999 -1.499 270)
			(size 1.1 1.1)
			(drill 1.1)
			(layers "*.Cu" "*.Mask")
		)
		(pad "" np_thru_hole circle
			(at 9.999 -1.499 270)
			(size 1.6 1.6)
			(drill 1.6)
			(layers "*.Cu" "*.Mask")
		)
		(pad "1" smd rect
			(at -9.249 3.749 270)
			(size 0.3 1.55)
			(layers "B.Cu" "B.Mask" "B.Paste")
			(net 1 "GND")
			(pinfunction "GND")
			(pintype "power_in")
		)
		(pad "2" smd rect
			(at -9.001 -3.749 270)
			(size 0.3 1.55)
			(layers "B.Cu" "B.Mask" "B.Paste")
			(net 2 "+3V3")
			(pinfunction "3.3V")
			(pintype "power_in")
		)
		(pad "3" smd rect
			(at -8.751 3.749 270)
			(size 0.3 1.55)
			(layers "B.Cu" "B.Mask" "B.Paste")
			(net 272 "/M.2/WIFI_BT_USB_D_P")
			(pinfunction "USB_D_P")
			(pintype "bidirectional")
		)
		(pad "4" smd rect
			(at -8.501 -3.749 270)
			(size 0.3 1.55)
			(layers "B.Cu" "B.Mask" "B.Paste")
			(net 2 "+3V3")
			(pinfunction "3.3V")
			(pintype "passive")
		)
		(pad "5" smd rect
			(at -8.251 3.749 270)
			(size 0.3 1.55)
			(layers "B.Cu" "B.Mask" "B.Paste")
			(net 259 "/M.2/WIFI_BT_USB_D_N")
			(pinfunction "USB_D_N")
			(pintype "bidirectional")
		)
		(pad "6" smd rect
			(at -8 -3.749 270)
			(size 0.3 1.55)
			(layers "B.Cu" "B.Mask" "B.Paste")
			(net 34 "/M.2/~{LED_1}")
			(pinfunction "~{LED_1}")
			(pintype "output")
		)
		(pad "7" smd rect
			(at -7.75 3.749 270)
			(size 0.3 1.55)
			(layers "B.Cu" "B.Mask" "B.Paste")
			(net 1 "GND")
			(pinfunction "GND")
			(pintype "passive")
		)
		(pad "8" smd rect
			(at -7.5 -3.749 270)
			(size 0.3 1.55)
			(layers "B.Cu" "B.Mask" "B.Paste")
			(net 255 "unconnected-(J14-PCM_CLK-Pad8)")
			(pinfunction "PCM_CLK")
			(pintype "bidirectional+no_connect")
		)
		(pad "9" smd rect
			(at -7.25 3.749 270)
			(size 0.3 1.55)
			(layers "B.Cu" "B.Mask" "B.Paste")
			(net 277 "unconnected-(J14-SDIO_CLK-Pad9)")
			(pinfunction "SDIO_CLK")
			(pintype "input+no_connect")
		)
		(pad "10" smd rect
			(at -7 -3.749 270)
			(size 0.3 1.55)
			(layers "B.Cu" "B.Mask" "B.Paste")
			(net 1007 "unconnected-(J14-PCM_SYNC-Pad10)")
			(pinfunction "PCM_SYNC")
			(pintype "bidirectional+no_connect")
		)
		(pad "11" smd rect
			(at -6.75 3.749 270)
			(size 0.3 1.55)
			(layers "B.Cu" "B.Mask" "B.Paste")
			(net 254 "unconnected-(J14-SDIO_CMD-Pad11)")
			(pinfunction "SDIO_CMD")
			(pintype "bidirectional+no_connect")
		)
		(pad "12" smd rect
			(at -6.5 -3.749 270)
			(size 0.3 1.55)
			(layers "B.Cu" "B.Mask" "B.Paste")
			(net 1006 "unconnected-(J14-PCM_IN-Pad12)")
			(pinfunction "PCM_IN")
			(pintype "bidirectional+no_connect")
		)
		(pad "13" smd rect
			(at -6.25 3.749 270)
			(size 0.3 1.55)
			(layers "B.Cu" "B.Mask" "B.Paste")
			(net 268 "unconnected-(J14-SDIO_D0-Pad13)")
			(pinfunction "SDIO_D0")
			(pintype "bidirectional+no_connect")
		)
		(pad "14" smd rect
			(at -6 -3.749 270)
			(size 0.3 1.55)
			(layers "B.Cu" "B.Mask" "B.Paste")
			(net 274 "unconnected-(J14-PCM_OUT-Pad14)")
			(pinfunction "PCM_OUT")
			(pintype "bidirectional+no_connect")
		)
		(pad "15" smd rect
			(at -5.75 3.749 270)
			(size 0.3 1.55)
			(layers "B.Cu" "B.Mask" "B.Paste")
			(net 262 "unconnected-(J14-SDIO_D1-Pad15)")
			(pinfunction "SDIO_D1")
			(pintype "bidirectional+no_connect")
		)
		(pad "16" smd rect
			(at -5.5 -3.749 270)
			(size 0.3 1.55)
			(layers "B.Cu" "B.Mask" "B.Paste")
			(net 35 "/M.2/~{LED_2}")
			(pinfunction "~{LED_2}")
			(pintype "output")
		)
		(pad "17" smd rect
			(at -5.25 3.749 270)
			(size 0.3 1.55)
			(layers "B.Cu" "B.Mask" "B.Paste")
			(net 266 "unconnected-(J14-SDIO_D2-Pad17)")
			(pinfunction "SDIO_D2")
			(pintype "bidirectional+no_connect")
		)
		(pad "18" smd rect
			(at -5.001 -3.749 270)
			(size 0.3 1.55)
			(layers "B.Cu" "B.Mask" "B.Paste")
			(net 1 "GND")
			(pinfunction "GND")
			(pintype "passive")
		)
		(pad "19" smd rect
			(at -4.751 3.749 270)
			(size 0.3 1.55)
			(layers "B.Cu" "B.Mask" "B.Paste")
			(net 258 "unconnected-(J14-SDIO_D3-Pad19)")
			(pinfunction "SDIO_D3")
			(pintype "bidirectional+no_connect")
		)
		(pad "20" smd rect
			(at -4.501 -3.749 270)
			(size 0.3 1.55)
			(layers "B.Cu" "B.Mask" "B.Paste")
			(net 1337 "unconnected-(J14-~{UART_WAKE}-Pad20)")
			(pinfunction "~{UART_WAKE}")
			(pintype "output+no_connect")
		)
		(pad "21" smd rect
			(at -4.251 3.749 270)
			(size 0.3 1.55)
			(layers "B.Cu" "B.Mask" "B.Paste")
			(net 240 "unconnected-(J14-SDIO_~{WAKE}-Pad21)")
			(pinfunction "SDIO_~{WAKE}")
			(pintype "bidirectional+no_connect")
		)
		(pad "22" smd rect
			(at -4.001 -3.749 270)
			(size 0.3 1.55)
			(layers "B.Cu" "B.Mask" "B.Paste")
			(net 250 "unconnected-(J14-UART_RXD-Pad22)")
			(pinfunction "UART_RXD")
			(pintype "bidirectional+no_connect")
		)
		(pad "23" smd rect
			(at -3.75 3.749 270)
			(size 0.3 1.55)
			(layers "B.Cu" "B.Mask" "B.Paste")
			(net 275 "unconnected-(J14-SDIO_~{RESET}-Pad23)")
			(pinfunction "SDIO_~{RESET}")
			(pintype "input+no_connect")
		)
		(pad "32" smd rect
			(at -1.5 -3.749 270)
			(size 0.3 1.55)
			(layers "B.Cu" "B.Mask" "B.Paste")
			(net 263 "unconnected-(J14-UART_TXD-Pad32)")
			(pinfunction "UART_TXD")
			(pintype "bidirectional+no_connect")
		)
		(pad "33" smd rect
			(at -1.25 3.749 270)
			(size 0.3 1.55)
			(layers "B.Cu" "B.Mask" "B.Paste")
			(net 1 "GND")
			(pinfunction "GND")
			(pintype "passive")
		)
		(pad "34" smd rect
			(at -1 -3.749 270)
			(size 0.3 1.55)
			(layers "B.Cu" "B.Mask" "B.Paste")
			(net 273 "unconnected-(J14-UART_CTS-Pad34)")
			(pinfunction "UART_CTS")
			(pintype "bidirectional+no_connect")
		)
		(pad "35" smd rect
			(at -0.75 3.749 270)
			(size 0.3 1.55)
			(layers "B.Cu" "B.Mask" "B.Paste")
			(net 444 "/M.2/M2_E_PET0_N")
			(pinfunction "PET0_P")
			(pintype "input")
		)
		(pad "36" smd rect
			(at -0.5 -3.749 270)
			(size 0.3 1.55)
			(layers "B.Cu" "B.Mask" "B.Paste")
			(net 267 "unconnected-(J14-UART_RTS-Pad36)")
			(pinfunction "UART_RTS")
			(pintype "bidirectional+no_connect")
		)
		(pad "37" smd rect
			(at -0.25 3.749 270)
			(size 0.3 1.55)
			(layers "B.Cu" "B.Mask" "B.Paste")
			(net 440 "/M.2/M2_E_PET0_P")
			(pinfunction "PET0_N")
			(pintype "input")
		)
		(pad "38" smd rect
			(at 0 -3.749 270)
			(size 0.3 1.55)
			(layers "B.Cu" "B.Mask" "B.Paste")
			(net 1336 "unconnected-(J14-VENDOR_1-Pad38)")
			(pinfunction "VENDOR_1")
			(pintype "bidirectional+no_connect")
		)
		(pad "39" smd rect
			(at 0.25 3.749 270)
			(size 0.3 1.55)
			(layers "B.Cu" "B.Mask" "B.Paste")
			(net 1 "GND")
			(pinfunction "GND")
			(pintype "passive")
		)
		(pad "40" smd rect
			(at 0.5 -3.749 270)
			(size 0.3 1.55)
			(layers "B.Cu" "B.Mask" "B.Paste")
			(net 1334 "unconnected-(J14-VENDOR_2-Pad40)")
			(pinfunction "VENDOR_2")
			(pintype "bidirectional+no_connect")
		)
		(pad "41" smd rect
			(at 0.75 3.749 270)
			(size 0.3 1.55)
			(layers "B.Cu" "B.Mask" "B.Paste")
			(net 130 "/M.2/PCIe_{C1x1}.RX0+")
			(pinfunction "PER0_P")
			(pintype "output")
		)
		(pad "42" smd rect
			(at 1 -3.749 270)
			(size 0.3 1.55)
			(layers "B.Cu" "B.Mask" "B.Paste")
			(net 1335 "unconnected-(J14-VENDOR_3-Pad42)")
			(pinfunction "VENDOR_3")
			(pintype "bidirectional+no_connect")
		)
		(pad "43" smd rect
			(at 1.25 3.749 270)
			(size 0.3 1.55)
			(layers "B.Cu" "B.Mask" "B.Paste")
			(net 94 "/M.2/PCIe_{C1x1}.RX0-")
			(pinfunction "PER0_N")
			(pintype "output")
		)
		(pad "44" smd rect
			(at 1.5 -3.749 270)
			(size 0.3 1.55)
			(layers "B.Cu" "B.Mask" "B.Paste")
			(net 248 "unconnected-(J14-COEX3-Pad44)")
			(pinfunction "COEX3")
			(pintype "bidirectional+no_connect")
		)
		(pad "45" smd rect
			(at 1.75 3.749 270)
			(size 0.3 1.55)
			(layers "B.Cu" "B.Mask" "B.Paste")
			(net 1 "GND")
			(pinfunction "GND")
			(pintype "passive")
		)
		(pad "46" smd rect
			(at 2 -3.749 270)
			(size 0.3 1.55)
			(layers "B.Cu" "B.Mask" "B.Paste")
			(net 261 "unconnected-(J14-COEX_TXD-Pad46)")
			(pinfunction "COEX_TXD")
			(pintype "bidirectional+no_connect")
		)
		(pad "47" smd rect
			(at 2.25 3.749 270)
			(size 0.3 1.55)
			(layers "B.Cu" "B.Mask" "B.Paste")
			(net 676 "/M.2/PCIe_{C1x1}.CLK-")
			(pinfunction "REFCLK0_P")
			(pintype "input")
		)
		(pad "48" smd rect
			(at 2.5 -3.749 270)
			(size 0.3 1.55)
			(layers "B.Cu" "B.Mask" "B.Paste")
			(net 252 "unconnected-(J14-COEX_RXD-Pad48)")
			(pinfunction "COEX_RXD")
			(pintype "bidirectional+no_connect")
		)
		(pad "49" smd rect
			(at 2.75 3.749 270)
			(size 0.3 1.55)
			(layers "B.Cu" "B.Mask" "B.Paste")
			(net 589 "/M.2/PCIe_{C1x1}.CLK+")
			(pinfunction "REFCLK0_N")
			(pintype "input")
		)
		(pad "50" smd rect
			(at 3 -3.749 270)
			(size 0.3 1.55)
			(layers "B.Cu" "B.Mask" "B.Paste")
			(net 832 "/M.2/M2_E_SUSCLK")
			(pinfunction "SUSCLK")
			(pintype "input")
		)
		(pad "51" smd rect
			(at 3.25 3.749 270)
			(size 0.3 1.55)
			(layers "B.Cu" "B.Mask" "B.Paste")
			(net 1 "GND")
			(pinfunction "GND")
			(pintype "passive")
		)
		(pad "52" smd rect
			(at 3.5 -3.749 270)
			(size 0.3 1.55)
			(layers "B.Cu" "B.Mask" "B.Paste")
			(net 831 "/M.2/~{PERST_E}")
			(pinfunction "~{PERST0}")
			(pintype "input")
		)
		(pad "53" smd rect
			(at 3.75 3.749 270)
			(size 0.3 1.55)
			(layers "B.Cu" "B.Mask" "B.Paste")
			(net 834 "/M.2/~{CLKREQ_E}")
			(pinfunction "~{CLKREQ0}")
			(pintype "output")
		)
		(pad "54" smd rect
			(at 4 -3.749 270)
			(size 0.3 1.55)
			(layers "B.Cu" "B.Mask" "B.Paste")
			(net 247 "/M.2/M2_E_W_DIS_2")
			(pinfunction "W_DISABLE2")
			(pintype "input")
		)
		(pad "55" smd rect
			(at 4.25 3.749 270)
			(size 0.3 1.55)
			(layers "B.Cu" "B.Mask" "B.Paste")
			(net 833 "/M.2/~{PEWAKE_E}")
			(pinfunction "~{PEWAKE0}")
			(pintype "output")
		)
		(pad "56" smd rect
			(at 4.5 -3.749 270)
			(size 0.3 1.55)
			(layers "B.Cu" "B.Mask" "B.Paste")
			(net 244 "/M.2/M2_E_W_DIS_1")
			(pinfunction "W_DISABLE1")
			(pintype "input")
		)
		(pad "57" smd rect
			(at 4.75 3.749 270)
			(size 0.3 1.55)
			(layers "B.Cu" "B.Mask" "B.Paste")
			(net 1 "GND")
			(pinfunction "GND")
			(pintype "passive")
		)
		(pad "58" smd rect
			(at 5 -3.749 270)
			(size 0.3 1.55)
			(layers "B.Cu" "B.Mask" "B.Paste")
			(net 256 "unconnected-(J14-I2C_DATA-Pad58)")
			(pinfunction "I2C_DATA")
			(pintype "bidirectional+no_connect")
		)
		(pad "59" smd rect
			(at 5.25 3.749 270)
			(size 0.3 1.55)
			(layers "B.Cu" "B.Mask" "B.Paste")
			(net 830 "unconnected-(J14-PET1_P-Pad59)")
			(pinfunction "PET1_P")
			(pintype "input+no_connect")
		)
		(pad "60" smd rect
			(at 5.5 -3.749 270)
			(size 0.3 1.55)
			(layers "B.Cu" "B.Mask" "B.Paste")
			(net 264 "unconnected-(J14-I2C_CLK-Pad60)")
			(pinfunction "I2C_CLK")
			(pintype "bidirectional+no_connect")
		)
		(pad "61" smd rect
			(at 5.75 3.749 270)
			(size 0.3 1.55)
			(layers "B.Cu" "B.Mask" "B.Paste")
			(net 835 "unconnected-(J14-PET1_N-Pad61)")
			(pinfunction "PET1_N")
			(pintype "input+no_connect")
		)
		(pad "62" smd rect
			(at 6 -3.749 270)
			(size 0.3 1.55)
			(layers "B.Cu" "B.Mask" "B.Paste")
			(net 257 "/M.2/~{M2_E_ALERT}")
			(pinfunction "~{ALERT}")
			(pintype "output")
		)
		(pad "63" smd rect
			(at 6.25 3.749 270)
			(size 0.3 1.55)
			(layers "B.Cu" "B.Mask" "B.Paste")
			(net 1 "GND")
			(pinfunction "GND")
			(pintype "passive")
		)
		(pad "64" smd rect
			(at 6.5 -3.749 270)
			(size 0.3 1.55)
			(layers "B.Cu" "B.Mask" "B.Paste")
			(net 251 "unconnected-(J14-RFU-Pad64)")
			(pinfunction "RFU")
			(pintype "no_connect")
		)
		(pad "65" smd rect
			(at 6.75 3.749 270)
			(size 0.3 1.55)
			(layers "B.Cu" "B.Mask" "B.Paste")
			(net 828 "unconnected-(J14-PER1_P-Pad65)")
			(pinfunction "PER1_P")
			(pintype "output+no_connect")
		)
		(pad "66" smd rect
			(at 6.999 -3.749 270)
			(size 0.3 1.55)
			(layers "B.Cu" "B.Mask" "B.Paste")
			(net 276 "unconnected-(J14-UIM_SWP-Pad66)")
			(pinfunction "UIM_SWP")
			(pintype "bidirectional+no_connect")
		)
		(pad "67" smd rect
			(at 7.249 3.749 270)
			(size 0.3 1.55)
			(layers "B.Cu" "B.Mask" "B.Paste")
			(net 829 "unconnected-(J14-PER1_N-Pad67)")
			(pinfunction "PER1_N")
			(pintype "output+no_connect")
		)
		(pad "68" smd rect
			(at 7.499 -3.749 270)
			(size 0.3 1.55)
			(layers "B.Cu" "B.Mask" "B.Paste")
			(net 265 "unconnected-(J14-UIM_POWER_SNK-Pad68)")
			(pinfunction "UIM_POWER_SNK")
			(pintype "bidirectional+no_connect")
		)
		(pad "69" smd rect
			(at 7.749 3.749 270)
			(size 0.3 1.55)
			(layers "B.Cu" "B.Mask" "B.Paste")
			(net 1 "GND")
			(pinfunction "GND")
			(pintype "passive")
		)
		(pad "70" smd rect
			(at 7.999 -3.749 270)
			(size 0.3 1.55)
			(layers "B.Cu" "B.Mask" "B.Paste")
			(net 278 "unconnected-(J14-UIM_POWER_SRC-Pad70)")
			(pinfunction "UIM_POWER_SRC")
			(pintype "bidirectional+no_connect")
		)
		(pad "71" smd rect
			(at 8.249 3.749 270)
			(size 0.3 1.55)
			(layers "B.Cu" "B.Mask" "B.Paste")
			(net 836 "unconnected-(J14-REFCLK1_P-Pad71)")
			(pinfunction "REFCLK1_P")
			(pintype "input+no_connect")
		)
		(pad "72" smd rect
			(at 8.499 -3.749 270)
			(size 0.3 1.55)
			(layers "B.Cu" "B.Mask" "B.Paste")
			(net 2 "+3V3")
			(pinfunction "3.3V")
			(pintype "passive")
		)
		(pad "73" smd rect
			(at 8.749 3.749 270)
			(size 0.3 1.55)
			(layers "B.Cu" "B.Mask" "B.Paste")
			(net 837 "unconnected-(J14-REFCLK1_N-Pad73)")
			(pinfunction "REFCLK1_N")
			(pintype "input+no_connect")
		)
		(pad "74" smd rect
			(at 8.999 -3.749 270)
			(size 0.3 1.55)
			(layers "B.Cu" "B.Mask" "B.Paste")
			(net 2 "+3V3")
			(pinfunction "3.3V")
			(pintype "passive")
		)
		(pad "75" smd rect
			(at 9.249 3.749 270)
			(size 0.3 1.55)
			(layers "B.Cu" "B.Mask" "B.Paste")
			(net 1 "GND")
			(pinfunction "GND")
			(pintype "passive")
		)
		(pad "MP" smd rect
			(at -10.35 3.001 270)
			(size 1.2 2.75)
			(layers "B.Cu" "B.Mask" "B.Paste")
			(net 1 "GND")
			(pinfunction "MP")
			(pintype "passive")
		)
		(pad "MP" smd rect
			(at 10.351 3.001 270)
			(size 1.2 2.75)
			(layers "B.Cu" "B.Mask" "B.Paste")
			(net 1 "GND")
			(pinfunction "MP")
			(pintype "passive")
		)
	)
)
